# T6G (Grand Teton) — schematic netlist excerpt (pin names and nets, part order shuffled) for the footprints in the layout excerpt that follows; sources: Cadence DE-HDL packaged netlist, KiCad conversion of 04192023_DAF0TMB3IC0_F0TG_MB_C_brd_V02_OCP.brd

C513  Q_CAP  1UF 4V 20% X6S  pkg 0201  page 279 : A = P1V8_CPU0_RT0_1A_1D ; B = GND
R8222  Q_RES  1K 1% EMPTY  pkg 0402LF  page 217 : A = PVDD18_S5_P1 ; B = SVID_PVDDCR_CPU1_P1_SVD_R
PC166_6  Q_CAP  22UF 4V 20% X6S  pkg C0805  page 196 : A = PVDDCR_CPU0_P0 ; B = GND

(kicad_pcb
	(version 20260206)
	(generator "pcbnew")
	(generator_version "10.0")
	(general
		(thickness 1.6)
		(legacy_teardrops no)
	)
	(paper "A4")
	(title_block
		(title "04192023_DAF0TMB3IC0_F0TG_MB_C_brd_V02_OCP.brd")
		(comment 1 "Grand Teton / footprints 6311-6313 of 8354")
	)
	(layers
		(0 "F.Cu" signal "TOP")
		(4 "In1.Cu" signal "GND")
		(6 "In2.Cu" signal "IN1")
		(8 "In3.Cu" signal "GND1")
		(10 "In4.Cu" signal "IN2")
		(12 "In5.Cu" signal "GND2")
		(14 "In6.Cu" signal "IN3")
		(16 "In7.Cu" signal "GND3")
		(18 "In8.Cu" signal "VCC")
		(20 "In9.Cu" signal "VCC1")
		(22 "In10.Cu" signal "GND4")
		(24 "In11.Cu" signal "IN4")
		(26 "In12.Cu" signal "GND5")
		(28 "In13.Cu" signal "IN5")
		(30 "In14.Cu" signal "GND6")
		(32 "In15.Cu" signal "IN6")
		(34 "In16.Cu" signal "GND7")
		(2 "B.Cu" signal "BOTTOM")
		(9 "F.Adhes" user "F.Adhesive")
		(11 "B.Adhes" user "B.Adhesive")
		(13 "F.Paste" user "Package Geometry/Pastemask Top")
		(15 "B.Paste" user "Package Geometry/Pastemask Bottom")
		(5 "F.SilkS" user "Ref Des/Silkscreen Top")
		(7 "B.SilkS" user "Ref Des/Silkscreen Bottom")
		(1 "F.Mask" user "Board Geometry/Soldermask Top")
		(3 "B.Mask" user "Board Geometry/Soldermask Bottom")
		(17 "Dwgs.User" user "User.Drawings")
		(19 "Cmts.User" user "User.Comments")
		(21 "Eco1.User" user "User.Eco1")
		(23 "Eco2.User" user "User.Eco2")
		(25 "Edge.Cuts" user "Board Geometry/Outline")
		(27 "Margin" user)
		(31 "F.CrtYd" user "Package Geometry/Place Bound Top")
		(29 "B.CrtYd" user "Package Geometry/Place Bound Bottom")
		(35 "F.Fab" user "Ref Des/Assembly Top")
		(33 "B.Fab" user "Ref Des/Assembly Bottom")
	)
	(footprint ""
		(layer "B.Cu")
		(at 314.178188 -395.148562 90)
		(property "Reference" "C513"
			(at 0 0 90)
			(layer "B.SilkS")
			(hide yes)
			(effects
				(font
					(size 1.27 1.27)
				)
				(justify mirror)
			)
		)
		(property "Value" ""
			(at 0 0 90)
			(layer "B.Fab")
			(effects
				(font
					(size 1.27 1.27)
				)
				(justify mirror)
			)
		)
		(duplicate_pad_numbers_are_jumpers no)
		(fp_line
			(start 0.299974 -0.150114)
			(end -0.299974 -0.150114)
			(stroke
				(width 0.1)
				(type default)
			)
			(layer "B.Fab")
		)
		(fp_line
			(start -0.299974 -0.150114)
			(end -0.299974 0.150114)
			(stroke
				(width 0.1)
				(type default)
			)
			(layer "B.Fab")
		)
		(fp_line
			(start 0.299974 0.150114)
			(end 0.299974 -0.150114)
			(stroke
				(width 0.1)
				(type default)
			)
			(layer "B.Fab")
		)
		(fp_line
			(start -0.299974 0.150114)
			(end 0.299974 0.150114)
			(stroke
				(width 0.1)
				(type default)
			)
			(layer "B.Fab")
		)
		(pad "1" smd rect
			(at 0.2667 0 270)
			(size 0.3048 0.381)
			(layers "B.Cu" "B.Mask" "B.Paste")
			(net "P1V8_CPU0_RT0_1A_1D")
		)
		(pad "2" smd rect
			(at -0.2667 0 270)
			(size 0.3048 0.381)
			(layers "B.Cu" "B.Mask" "B.Paste")
			(net "GND")
		)
	)
	(footprint ""
		(layer "B.Cu")
		(at 22.479 -361.061 180)
		(property "Reference" "R8222"
			(at 0 0 0)
			(layer "B.SilkS")
			(hide yes)
			(effects
				(font
					(size 1.27 1.27)
				)
				(justify mirror)
			)
		)
		(property "Value" ""
			(at 0 0 0)
			(layer "B.Fab")
			(effects
				(font
					(size 1.27 1.27)
				)
				(justify mirror)
			)
		)
		(duplicate_pad_numbers_are_jumpers no)
		(fp_line
			(start 0.7874 0.4064)
			(end 0.7874 -0.4064)
			(stroke
				(width 0.1524)
				(type default)
			)
			(layer "B.SilkS")
		)
		(fp_line
			(start 0.7874 -0.4064)
			(end -0.7874 -0.4064)
			(stroke
				(width 0.1524)
				(type default)
			)
			(layer "B.SilkS")
		)
		(fp_line
			(start -0.7874 0.4064)
			(end 0.7874 0.4064)
			(stroke
				(width 0.1524)
				(type default)
			)
			(layer "B.SilkS")
		)
		(fp_line
			(start -0.7874 -0.4064)
			(end -0.7874 0.4064)
			(stroke
				(width 0.1524)
				(type default)
			)
			(layer "B.SilkS")
		)
		(fp_line
			(start 0.67945 0.3048)
			(end 0.67945 -0.305054)
			(stroke
				(width 0.1)
				(type default)
			)
			(layer "B.Fab")
		)
		(fp_line
			(start 0.67945 -0.305054)
			(end 0.12065 -0.305054)
			(stroke
				(width 0.1)
				(type default)
			)
			(layer "B.Fab")
		)
		(fp_line
			(start 0.12065 0.3048)
			(end 0.67945 0.3048)
			(stroke
				(width 0.1)
				(type default)
			)
			(layer "B.Fab")
		)
		(fp_line
			(start 0.12065 0.2794)
			(end 0.12065 0.3048)
			(stroke
				(width 0.1)
				(type default)
			)
			(layer "B.Fab")
		)
		(fp_line
			(start 0.12065 -0.2794)
			(end -0.12065 -0.2794)
			(stroke
				(width 0.1)
				(type default)
			)
			(layer "B.Fab")
		)
		(fp_line
			(start 0.12065 -0.305054)
			(end 0.12065 -0.2794)
			(stroke
				(width 0.1)
				(type default)
			)
			(layer "B.Fab")
		)
		(fp_line
			(start -0.120396 0.3048)
			(end -0.120396 0.2794)
			(stroke
				(width 0.1)
				(type default)
			)
			(layer "B.Fab")
		)
		(fp_line
			(start -0.120396 0.2794)
			(end 0.12065 0.2794)
			(stroke
				(width 0.1)
				(type default)
			)
			(layer "B.Fab")
		)
		(fp_line
			(start -0.12065 -0.2794)
			(end -0.12065 -0.3048)
			(stroke
				(width 0.1)
				(type default)
			)
			(layer "B.Fab")
		)
		(fp_line
			(start -0.12065 -0.3048)
			(end -0.67945 -0.3048)
			(stroke
				(width 0.1)
				(type default)
			)
			(layer "B.Fab")
		)
		(fp_line
			(start -0.67945 0.3048)
			(end -0.120396 0.3048)
			(stroke
				(width 0.1)
				(type default)
			)
			(layer "B.Fab")
		)
		(fp_line
			(start -0.67945 -0.3048)
			(end -0.67945 0.3048)
			(stroke
				(width 0.1)
				(type default)
			)
			(layer "B.Fab")
		)
		(pad "1" smd circle
			(at 0.40005 0)
			(size 0 0)
			(layers "B.Cu" "B.Mask" "B.Paste")
			(net "PVDD18_S5_P1")
		)
		(pad "2" smd circle
			(at -0.40005 0)
			(size 0 0)
			(layers "B.Cu" "B.Mask" "B.Paste")
			(net "SVID_PVDDCR_CPU1_P1_SVD_R")
		)
	)
	(footprint ""
		(layer "B.Cu")
		(at 345.510612 -169.787062 90)
		(property "Reference" "PC166_6"
			(at 0 0 90)
			(layer "B.SilkS")
			(hide yes)
			(effects
				(font
					(size 1.27 1.27)
				)
				(justify mirror)
			)
		)
		(property "Value" ""
			(at 0 0 90)
			(layer "B.Fab")
			(effects
				(font
					(size 1.27 1.27)
				)
				(justify mirror)
			)
		)
		(duplicate_pad_numbers_are_jumpers no)
		(fp_line
			(start 1.524 -0.762)
			(end -1.524 -0.762)
			(stroke
				(width 0.1524)
				(type default)
			)
			(layer "B.SilkS")
		)
		(fp_line
			(start -1.524 -0.762)
			(end -1.524 0.762)
			(stroke
				(width 0.1524)
				(type default)
			)
			(layer "B.SilkS")
		)
		(fp_line
			(start 1.524 0.762)
			(end 1.524 -0.762)
			(stroke
				(width 0.1524)
				(type default)
			)
			(layer "B.SilkS")
		)
		(fp_line
			(start -1.524 0.762)
			(end 1.524 0.762)
			(stroke
				(width 0.1524)
				(type default)
			)
			(layer "B.SilkS")
		)
		(fp_line
			(start 1.1049 -0.724916)
			(end 1.1049 0.724916)
			(stroke
				(width 0.1)
				(type default)
			)
			(layer "B.Fab")
		)
		(fp_line
			(start -1.1049 -0.724916)
			(end 1.1049 -0.724916)
			(stroke
				(width 0.1)
				(type default)
			)
			(layer "B.Fab")
		)
		(fp_line
			(start 1.1049 0.724916)
			(end -1.1049 0.724916)
			(stroke
				(width 0.1)
				(type default)
			)
			(layer "B.Fab")
		)
		(fp_line
			(start -1.1049 0.724916)
			(end -1.1049 -0.724916)
			(stroke
				(width 0.1)
				(type default)
			)
			(layer "B.Fab")
		)
		(pad "1" smd rect
			(at 0.889 0 90)
			(size 1.016 1.27)
			(layers "B.Cu" "B.Mask" "B.Paste")
			(net "PVDDCR_CPU0_P0")
		)
		(pad "2" smd rect
			(at -0.889 0 90)
			(size 1.016 1.27)
			(layers "B.Cu" "B.Mask" "B.Paste")
			(net "GND")
		)
	)
)
